(kicad_pcb
	(version 20260206)
	(generator "pcbnew")
	(generator_version "10.0")
	(general
		(thickness 1.6)
		(legacy_teardrops no)
	)
	(paper "A4")
	(title_block
		(title "12092022_DA0F0TMDCD0_F0T_Management_Board_D_brd_V3_OCP.brd")
		(comment 1 "Grand Teton / footprints 389-394 of 1440")
	)
	(layers
		(0 "F.Cu" signal "TOP")
		(4 "In1.Cu" signal "GND")
		(6 "In2.Cu" signal "IN1")
		(8 "In3.Cu" signal "GND1")
		(10 "In4.Cu" signal "IN2")
		(12 "In5.Cu" signal "VCC")
		(14 "In6.Cu" signal "VCC1")
		(16 "In7.Cu" signal "IN3")
		(18 "In8.Cu" signal "GND2")
		(20 "In9.Cu" signal "IN4")
		(22 "In10.Cu" signal "GND3")
		(2 "B.Cu" signal "BOTTOM")
		(9 "F.Adhes" user "F.Adhesive")
		(11 "B.Adhes" user "B.Adhesive")
		(13 "F.Paste" user "Package Geometry/Pastemask Top")
		(15 "B.Paste" user "Package Geometry/Pastemask Bottom")
		(5 "F.SilkS" user "Ref Des/Silkscreen Top")
		(7 "B.SilkS" user "Ref Des/Silkscreen Bottom")
		(1 "F.Mask" user "Board Geometry/Soldermask Top")
		(3 "B.Mask" user "Board Geometry/Soldermask Bottom")
		(17 "Dwgs.User" user "User.Drawings")
		(19 "Cmts.User" user "User.Comments")
		(21 "Eco1.User" user "User.Eco1")
		(23 "Eco2.User" user "User.Eco2")
		(25 "Edge.Cuts" user "Board Geometry/Outline")
		(27 "Margin" user)
		(31 "F.CrtYd" user "Package Geometry/Place Bound Top")
		(29 "B.CrtYd" user "Package Geometry/Place Bound Bottom")
		(35 "F.Fab" user "Ref Des/Assembly Top")
		(33 "B.Fab" user "Ref Des/Assembly Bottom")
	)
	(footprint ""
		(layer "F.Cu")
		(at 51.71313 -97.168716 90)
		(property "Reference" "Q1"
			(at 3.237484 -1.483614 0)
			(unlocked yes)
			(layer "F.SilkS")
			(effects
				(font
					(size 0.7874 0.5842)
					(thickness 0.1524)
				)
				(justify left)
			)
		)
		(property "Value" ""
			(at 0 0 90)
			(layer "F.Fab")
			(effects
				(font
					(size 1.27 1.27)
				)
			)
		)
		(duplicate_pad_numbers_are_jumpers no)
		(fp_line
			(start 1.905 -1.651)
			(end 1.905 1.651)
			(stroke
				(width 0.1524)
				(type default)
			)
			(layer "F.SilkS")
		)
		(fp_line
			(start -1.905 -1.651)
			(end 1.905 -1.651)
			(stroke
				(width 0.1524)
				(type default)
			)
			(layer "F.SilkS")
		)
		(fp_line
			(start 1.905 1.651)
			(end -1.905 1.651)
			(stroke
				(width 0.1524)
				(type default)
			)
			(layer "F.SilkS")
		)
		(fp_line
			(start -1.905 1.651)
			(end -1.905 -1.651)
			(stroke
				(width 0.1524)
				(type default)
			)
			(layer "F.SilkS")
		)
		(fp_line
			(start 0.6985 -1.524)
			(end 0.6985 -0.219964)
			(stroke
				(width 0.1)
				(type default)
			)
			(layer "F.Fab")
		)
		(fp_line
			(start -0.649986 -1.524)
			(end 0.6985 -1.524)
			(stroke
				(width 0.1)
				(type default)
			)
			(layer "F.Fab")
		)
		(fp_line
			(start -0.649986 -1.169924)
			(end -0.649986 -1.524)
			(stroke
				(width 0.1)
				(type default)
			)
			(layer "F.Fab")
		)
		(fp_line
			(start -1.249934 -1.169924)
			(end -0.649986 -1.169924)
			(stroke
				(width 0.1)
				(type default)
			)
			(layer "F.Fab")
		)
		(fp_line
			(start -0.6985 -0.729996)
			(end -1.249934 -0.729996)
			(stroke
				(width 0.1)
				(type default)
			)
			(layer "F.Fab")
		)
		(fp_line
			(start -1.249934 -0.729996)
			(end -1.249934 -1.169924)
			(stroke
				(width 0.1)
				(type default)
			)
			(layer "F.Fab")
		)
		(fp_line
			(start 1.249934 -0.219964)
			(end 1.249934 0.219964)
			(stroke
				(width 0.1)
				(type default)
			)
			(layer "F.Fab")
		)
		(fp_line
			(start 0.6985 -0.219964)
			(end 1.249934 -0.219964)
			(stroke
				(width 0.1)
				(type default)
			)
			(layer "F.Fab")
		)
		(fp_line
			(start 1.249934 0.219964)
			(end 0.6985 0.219964)
			(stroke
				(width 0.1)
				(type default)
			)
			(layer "F.Fab")
		)
		(fp_line
			(start 0.6985 0.219964)
			(end 0.6985 1.524)
			(stroke
				(width 0.1)
				(type default)
			)
			(layer "F.Fab")
		)
		(fp_line
			(start -0.6985 0.729996)
			(end -0.6985 -0.729996)
			(stroke
				(width 0.1)
				(type default)
			)
			(layer "F.Fab")
		)
		(fp_line
			(start -1.249934 0.729996)
			(end -0.6985 0.729996)
			(stroke
				(width 0.1)
				(type default)
			)
			(layer "F.Fab")
		)
		(fp_line
			(start -0.649986 1.169924)
			(end -1.249934 1.169924)
			(stroke
				(width 0.1)
				(type default)
			)
			(layer "F.Fab")
		)
		(fp_line
			(start -1.249934 1.169924)
			(end -1.249934 0.729996)
			(stroke
				(width 0.1)
				(type default)
			)
			(layer "F.Fab")
		)
		(fp_line
			(start 0.6985 1.524)
			(end -0.649986 1.524)
			(stroke
				(width 0.1)
				(type default)
			)
			(layer "F.Fab")
		)
		(fp_line
			(start -0.649986 1.524)
			(end -0.649986 1.169924)
			(stroke
				(width 0.1)
				(type default)
			)
			(layer "F.Fab")
		)
		(pad "B" smd rect
			(at -1.1176 -1.016)
			(size 1.016 1.27)
			(layers "F.Cu" "F.Mask" "F.Paste")
			(net "BJT_Q3_C")
		)
		(pad "C" smd rect
			(at 1.1176 0)
			(size 1.016 1.27)
			(layers "F.Cu" "F.Mask" "F.Paste")
			(net "RST_BMC_EXTRST_R2_N")
		)
		(pad "E" smd rect
			(at -1.1176 1.016)
			(size 1.016 1.27)
			(layers "F.Cu" "F.Mask" "F.Paste")
			(net "GND")
		)
	)
	(footprint ""
		(layer "F.Cu")
		(at 37.973 -58.674 -90)
		(property "Reference" "R874"
			(at 0 0 270)
			(layer "F.SilkS")
			(hide yes)
			(effects
				(font
					(size 1.27 1.27)
				)
			)
		)
		(property "Value" ""
			(at 0 0 270)
			(layer "F.Fab")
			(effects
				(font
					(size 1.27 1.27)
				)
			)
		)
		(duplicate_pad_numbers_are_jumpers no)
		(fp_line
			(start -0.7874 0.4064)
			(end -0.7874 -0.4064)
			(stroke
				(width 0.1524)
				(type default)
			)
			(layer "F.SilkS")
		)
		(fp_line
			(start 0.7874 0.4064)
			(end -0.7874 0.4064)
			(stroke
				(width 0.1524)
				(type default)
			)
			(layer "F.SilkS")
		)
		(fp_line
			(start -0.7874 -0.4064)
			(end 0.7874 -0.4064)
			(stroke
				(width 0.1524)
				(type default)
			)
			(layer "F.SilkS")
		)
		(fp_line
			(start 0.7874 -0.4064)
			(end 0.7874 0.4064)
			(stroke
				(width 0.1524)
				(type default)
			)
			(layer "F.SilkS")
		)
		(fp_line
			(start -0.67945 0.3048)
			(end -0.67945 -0.305054)
			(stroke
				(width 0.1)
				(type default)
			)
			(layer "F.Fab")
		)
		(fp_line
			(start -0.12065 0.3048)
			(end -0.67945 0.3048)
			(stroke
				(width 0.1)
				(type default)
			)
			(layer "F.Fab")
		)
		(fp_line
			(start 0.120396 0.3048)
			(end 0.120396 0.2794)
			(stroke
				(width 0.1)
				(type default)
			)
			(layer "F.Fab")
		)
		(fp_line
			(start 0.67945 0.3048)
			(end 0.120396 0.3048)
			(stroke
				(width 0.1)
				(type default)
			)
			(layer "F.Fab")
		)
		(fp_line
			(start -0.12065 0.2794)
			(end -0.12065 0.3048)
			(stroke
				(width 0.1)
				(type default)
			)
			(layer "F.Fab")
		)
		(fp_line
			(start 0.120396 0.2794)
			(end -0.12065 0.2794)
			(stroke
				(width 0.1)
				(type default)
			)
			(layer "F.Fab")
		)
		(fp_line
			(start -0.12065 -0.2794)
			(end 0.12065 -0.2794)
			(stroke
				(width 0.1)
				(type default)
			)
			(layer "F.Fab")
		)
		(fp_line
			(start 0.12065 -0.2794)
			(end 0.12065 -0.3048)
			(stroke
				(width 0.1)
				(type default)
			)
			(layer "F.Fab")
		)
		(fp_line
			(start 0.12065 -0.3048)
			(end 0.67945 -0.3048)
			(stroke
				(width 0.1)
				(type default)
			)
			(layer "F.Fab")
		)
		(fp_line
			(start 0.67945 -0.3048)
			(end 0.67945 0.3048)
			(stroke
				(width 0.1)
				(type default)
			)
			(layer "F.Fab")
		)
		(fp_line
			(start -0.67945 -0.305054)
			(end -0.12065 -0.305054)
			(stroke
				(width 0.1)
				(type default)
			)
			(layer "F.Fab")
		)
		(fp_line
			(start -0.12065 -0.305054)
			(end -0.12065 -0.2794)
			(stroke
				(width 0.1)
				(type default)
			)
			(layer "F.Fab")
		)
		(pad "1" smd circle
			(at -0.40005 0 270)
			(size 0 0)
			(layers "F.Cu" "F.Mask" "F.Paste")
			(net "PWRGD_P1V8_AUX_R3")
		)
		(pad "2" smd circle
			(at 0.40005 0 270)
			(size 0 0)
			(layers "F.Cu" "F.Mask" "F.Paste")
			(net "PWRGD_P1V8_AUX_R")
		)
	)
	(footprint ""
		(layer "F.Cu")
		(at 32.766 -44.45 90)
		(property "Reference" "C253"
			(at 0 0 90)
			(layer "F.SilkS")
			(hide yes)
			(effects
				(font
					(size 1.27 1.27)
				)
			)
		)
		(property "Value" ""
			(at 0 0 90)
			(layer "F.Fab")
			(effects
				(font
					(size 1.27 1.27)
				)
			)
		)
		(duplicate_pad_numbers_are_jumpers no)
		(fp_line
			(start 0.7874 -0.4064)
			(end 0.7874 0.4064)
			(stroke
				(width 0.1524)
				(type default)
			)
			(layer "F.SilkS")
		)
		(fp_line
			(start -0.7874 -0.4064)
			(end 0.7874 -0.4064)
			(stroke
				(width 0.1524)
				(type default)
			)
			(layer "F.SilkS")
		)
		(fp_line
			(start 0.7874 0.4064)
			(end -0.7874 0.4064)
			(stroke
				(width 0.1524)
				(type default)
			)
			(layer "F.SilkS")
		)
		(fp_line
			(start -0.7874 0.4064)
			(end -0.7874 -0.4064)
			(stroke
				(width 0.1524)
				(type default)
			)
			(layer "F.SilkS")
		)
		(fp_line
			(start -0.12065 -0.305054)
			(end -0.12065 -0.2794)
			(stroke
				(width 0.1)
				(type default)
			)
			(layer "F.Fab")
		)
		(fp_line
			(start -0.67945 -0.305054)
			(end -0.12065 -0.305054)
			(stroke
				(width 0.1)
				(type default)
			)
			(layer "F.Fab")
		)
		(fp_line
			(start 0.67945 -0.3048)
			(end 0.67945 0.3048)
			(stroke
				(width 0.1)
				(type default)
			)
			(layer "F.Fab")
		)
		(fp_line
			(start 0.12065 -0.3048)
			(end 0.67945 -0.3048)
			(stroke
				(width 0.1)
				(type default)
			)
			(layer "F.Fab")
		)
		(fp_line
			(start 0.12065 -0.2794)
			(end 0.12065 -0.3048)
			(stroke
				(width 0.1)
				(type default)
			)
			(layer "F.Fab")
		)
		(fp_line
			(start -0.12065 -0.2794)
			(end 0.12065 -0.2794)
			(stroke
				(width 0.1)
				(type default)
			)
			(layer "F.Fab")
		)
		(fp_line
			(start 0.120396 0.2794)
			(end -0.12065 0.2794)
			(stroke
				(width 0.1)
				(type default)
			)
			(layer "F.Fab")
		)
		(fp_line
			(start -0.12065 0.2794)
			(end -0.12065 0.3048)
			(stroke
				(width 0.1)
				(type default)
			)
			(layer "F.Fab")
		)
		(fp_line
			(start 0.67945 0.3048)
			(end 0.120396 0.3048)
			(stroke
				(width 0.1)
				(type default)
			)
			(layer "F.Fab")
		)
		(fp_line
			(start 0.120396 0.3048)
			(end 0.120396 0.2794)
			(stroke
				(width 0.1)
				(type default)
			)
			(layer "F.Fab")
		)
		(fp_line
			(start -0.12065 0.3048)
			(end -0.67945 0.3048)
			(stroke
				(width 0.1)
				(type default)
			)
			(layer "F.Fab")
		)
		(fp_line
			(start -0.67945 0.3048)
			(end -0.67945 -0.305054)
			(stroke
				(width 0.1)
				(type default)
			)
			(layer "F.Fab")
		)
		(pad "1" smd circle
			(at -0.40005 0 90)
			(size 0 0)
			(layers "F.Cu" "F.Mask" "F.Paste")
			(net "P3V3_AUX")
		)
		(pad "2" smd circle
			(at 0.40005 0 90)
			(size 0 0)
			(layers "F.Cu" "F.Mask" "F.Paste")
			(net "GND")
		)
	)
	(footprint ""
		(layer "F.Cu")
		(at 43.504104 -107.999784 -90)
		(property "Reference" "R488"
			(at 0 0 270)
			(layer "F.SilkS")
			(hide yes)
			(effects
				(font
					(size 1.27 1.27)
				)
			)
		)
		(property "Value" ""
			(at 0 0 270)
			(layer "F.Fab")
			(effects
				(font
					(size 1.27 1.27)
				)
			)
		)
		(duplicate_pad_numbers_are_jumpers no)
		(fp_line
			(start -0.7874 0.4064)
			(end -0.7874 -0.4064)
			(stroke
				(width 0.1524)
				(type default)
			)
			(layer "F.SilkS")
		)
		(fp_line
			(start 0.7874 0.4064)
			(end -0.7874 0.4064)
			(stroke
				(width 0.1524)
				(type default)
			)
			(layer "F.SilkS")
		)
		(fp_line
			(start -0.7874 -0.4064)
			(end 0.7874 -0.4064)
			(stroke
				(width 0.1524)
				(type default)
			)
			(layer "F.SilkS")
		)
		(fp_line
			(start 0.7874 -0.4064)
			(end 0.7874 0.4064)
			(stroke
				(width 0.1524)
				(type default)
			)
			(layer "F.SilkS")
		)
		(fp_line
			(start -0.67945 0.3048)
			(end -0.67945 -0.305054)
			(stroke
				(width 0.1)
				(type default)
			)
			(layer "F.Fab")
		)
		(fp_line
			(start -0.12065 0.3048)
			(end -0.67945 0.3048)
			(stroke
				(width 0.1)
				(type default)
			)
			(layer "F.Fab")
		)
		(fp_line
			(start 0.120396 0.3048)
			(end 0.120396 0.2794)
			(stroke
				(width 0.1)
				(type default)
			)
			(layer "F.Fab")
		)
		(fp_line
			(start 0.67945 0.3048)
			(end 0.120396 0.3048)
			(stroke
				(width 0.1)
				(type default)
			)
			(layer "F.Fab")
		)
		(fp_line
			(start -0.12065 0.2794)
			(end -0.12065 0.3048)
			(stroke
				(width 0.1)
				(type default)
			)
			(layer "F.Fab")
		)
		(fp_line
			(start 0.120396 0.2794)
			(end -0.12065 0.2794)
			(stroke
				(width 0.1)
				(type default)
			)
			(layer "F.Fab")
		)
		(fp_line
			(start -0.12065 -0.2794)
			(end 0.12065 -0.2794)
			(stroke
				(width 0.1)
				(type default)
			)
			(layer "F.Fab")
		)
		(fp_line
			(start 0.12065 -0.2794)
			(end 0.12065 -0.3048)
			(stroke
				(width 0.1)
				(type default)
			)
			(layer "F.Fab")
		)
		(fp_line
			(start 0.12065 -0.3048)
			(end 0.67945 -0.3048)
			(stroke
				(width 0.1)
				(type default)
			)
			(layer "F.Fab")
		)
		(fp_line
			(start 0.67945 -0.3048)
			(end 0.67945 0.3048)
			(stroke
				(width 0.1)
				(type default)
			)
			(layer "F.Fab")
		)
		(fp_line
			(start -0.67945 -0.305054)
			(end -0.12065 -0.305054)
			(stroke
				(width 0.1)
				(type default)
			)
			(layer "F.Fab")
		)
		(fp_line
			(start -0.12065 -0.305054)
			(end -0.12065 -0.2794)
			(stroke
				(width 0.1)
				(type default)
			)
			(layer "F.Fab")
		)
		(pad "1" smd circle
			(at -0.40005 0 270)
			(size 0 0)
			(layers "F.Cu" "F.Mask" "F.Paste")
			(net "P3V3_AUX")
		)
		(pad "2" smd circle
			(at 0.40005 0 270)
			(size 0 0)
			(layers "F.Cu" "F.Mask" "F.Paste")
			(net "SPI_PCH_IO2_FLASH_R1")
		)
	)
	(footprint ""
		(layer "F.Cu")
		(at 33.274 -54.356 -90)
		(property "Reference" "C293"
			(at 0 0 270)
			(layer "F.SilkS")
			(hide yes)
			(effects
				(font
					(size 1.27 1.27)
				)
			)
		)
		(property "Value" ""
			(at 0 0 270)
			(layer "F.Fab")
			(effects
				(font
					(size 1.27 1.27)
				)
			)
		)
		(duplicate_pad_numbers_are_jumpers no)
		(fp_line
			(start -1.651 0.8382)
			(end -1.651 -0.8382)
			(stroke
				(width 0.1524)
				(type default)
			)
			(layer "F.SilkS")
		)
		(fp_line
			(start 0 0.8382)
			(end 0 -0.8382)
			(stroke
				(width 0.1524)
				(type default)
			)
			(layer "F.SilkS")
		)
		(fp_line
			(start 1.651 0.8382)
			(end -1.651 0.8382)
			(stroke
				(width 0.1524)
				(type default)
			)
			(layer "F.SilkS")
		)
		(fp_line
			(start -1.651 -0.8382)
			(end 1.651 -0.8382)
			(stroke
				(width 0.1524)
				(type default)
			)
			(layer "F.SilkS")
		)
		(fp_line
			(start 1.651 -0.8382)
			(end 1.651 0.8382)
			(stroke
				(width 0.1524)
				(type default)
			)
			(layer "F.SilkS")
		)
		(fp_line
			(start -1.55956 0.7366)
			(end -1.524 0.7366)
			(stroke
				(width 0.1)
				(type default)
			)
			(layer "F.Fab")
		)
		(fp_line
			(start -1.524 0.7366)
			(end 1.524 0.7366)
			(stroke
				(width 0.1)
				(type default)
			)
			(layer "F.Fab")
		)
		(fp_line
			(start 1.524 0.7366)
			(end 1.55956 0.7366)
			(stroke
				(width 0.1)
				(type default)
			)
			(layer "F.Fab")
		)
		(fp_line
			(start 1.55956 0.7366)
			(end 1.55956 -0.7366)
			(stroke
				(width 0.1)
				(type default)
			)
			(layer "F.Fab")
		)
		(fp_line
			(start -1.55956 -0.7366)
			(end -1.55956 0.7366)
			(stroke
				(width 0.1)
				(type default)
			)
			(layer "F.Fab")
		)
		(fp_line
			(start -1.524 -0.7366)
			(end -1.55956 -0.7366)
			(stroke
				(width 0.1)
				(type default)
			)
			(layer "F.Fab")
		)
		(fp_line
			(start 1.524 -0.7366)
			(end -1.524 -0.7366)
			(stroke
				(width 0.1)
				(type default)
			)
			(layer "F.Fab")
		)
		(fp_line
			(start 1.55956 -0.7366)
			(end 1.524 -0.7366)
			(stroke
				(width 0.1)
				(type default)
			)
			(layer "F.Fab")
		)
		(pad "1" smd rect
			(at -0.94996 0 90)
			(size 1.1176 1.3716)
			(layers "F.Cu" "F.Mask" "F.Paste")
			(net "P3V3_AUX")
		)
		(pad "2" smd rect
			(at 0.94996 0 90)
			(size 1.1176 1.3716)
			(layers "F.Cu" "F.Mask" "F.Paste")
			(net "GND")
		)
	)
	(footprint ""
		(layer "F.Cu")
		(at 65.5066 -108.0008 -90)
		(property "Reference" "R311"
			(at 0 0 270)
			(layer "F.SilkS")
			(hide yes)
			(effects
				(font
					(size 1.27 1.27)
				)
			)
		)
		(property "Value" ""
			(at 0 0 270)
			(layer "F.Fab")
			(effects
				(font
					(size 1.27 1.27)
				)
			)
		)
		(duplicate_pad_numbers_are_jumpers no)
		(fp_line
			(start -0.7874 0.4064)
			(end -0.7874 -0.4064)
			(stroke
				(width 0.1524)
				(type default)
			)
			(layer "F.SilkS")
		)
		(fp_line
			(start 0.7874 0.4064)
			(end -0.7874 0.4064)
			(stroke
				(width 0.1524)
				(type default)
			)
			(layer "F.SilkS")
		)
		(fp_line
			(start -0.7874 -0.4064)
			(end 0.7874 -0.4064)
			(stroke
				(width 0.1524)
				(type default)
			)
			(layer "F.SilkS")
		)
		(fp_line
			(start 0.7874 -0.4064)
			(end 0.7874 0.4064)
			(stroke
				(width 0.1524)
				(type default)
			)
			(layer "F.SilkS")
		)
		(fp_line
			(start -0.67945 0.3048)
			(end -0.67945 -0.305054)
			(stroke
				(width 0.1)
				(type default)
			)
			(layer "F.Fab")
		)
		(fp_line
			(start -0.12065 0.3048)
			(end -0.67945 0.3048)
			(stroke
				(width 0.1)
				(type default)
			)
			(layer "F.Fab")
		)
		(fp_line
			(start 0.120396 0.3048)
			(end 0.120396 0.2794)
			(stroke
				(width 0.1)
				(type default)
			)
			(layer "F.Fab")
		)
		(fp_line
			(start 0.67945 0.3048)
			(end 0.120396 0.3048)
			(stroke
				(width 0.1)
				(type default)
			)
			(layer "F.Fab")
		)
		(fp_line
			(start -0.12065 0.2794)
			(end -0.12065 0.3048)
			(stroke
				(width 0.1)
				(type default)
			)
			(layer "F.Fab")
		)
		(fp_line
			(start 0.120396 0.2794)
			(end -0.12065 0.2794)
			(stroke
				(width 0.1)
				(type default)
			)
			(layer "F.Fab")
		)
		(fp_line
			(start -0.12065 -0.2794)
			(end 0.12065 -0.2794)
			(stroke
				(width 0.1)
				(type default)
			)
			(layer "F.Fab")
		)
		(fp_line
			(start 0.12065 -0.2794)
			(end 0.12065 -0.3048)
			(stroke
				(width 0.1)
				(type default)
			)
			(layer "F.Fab")
		)
		(fp_line
			(start 0.12065 -0.3048)
			(end 0.67945 -0.3048)
			(stroke
				(width 0.1)
				(type default)
			)
			(layer "F.Fab")
		)
		(fp_line
			(start 0.67945 -0.3048)
			(end 0.67945 0.3048)
			(stroke
				(width 0.1)
				(type default)
			)
			(layer "F.Fab")
		)
		(fp_line
			(start -0.67945 -0.305054)
			(end -0.12065 -0.305054)
			(stroke
				(width 0.1)
				(type default)
			)
			(layer "F.Fab")
		)
		(fp_line
			(start -0.12065 -0.305054)
			(end -0.12065 -0.2794)
			(stroke
				(width 0.1)
				(type default)
			)
			(layer "F.Fab")
		)
		(pad "1" smd circle
			(at -0.40005 0 270)
			(size 0 0)
			(layers "F.Cu" "F.Mask" "F.Paste")
			(net "ESPI_HOST_LPC_BMC_LFRAME_N")
		)
		(pad "2" smd circle
			(at 0.40005 0 270)
			(size 0 0)
			(layers "F.Cu" "F.Mask" "F.Paste")
			(net "ESPI_HOST_LPC_BMC_LFRAME_N_R")
		)
	)
)
